# SCM (Grand Teton) — schematic netlist excerpt (pin names and nets, part order shuffled) for the footprints in the layout excerpt that follows; sources: Cadence DE-HDL packaged netlist, KiCad conversion of 12092022_DA0F0TMDCD0_F0T_Management_Board_D_brd_V3_OCP.brd

R138  Q_RES  40.2 1% CHIP  pkg 0402LF  page 12 : A = SMB_BMC_MM4_R_SCL ; B = SMB_BMC_MM4_SCL
C257  Q_CAP  0.1UF 25V 10% X7R  pkg 0402  page 34 : A = PVCCIO_AUX_PLD ; B = GND

(kicad_pcb
	(version 20260206)
	(generator "pcbnew")
	(generator_version "10.0")
	(general
		(thickness 1.6)
		(legacy_teardrops no)
	)
	(paper "A4")
	(title_block
		(title "12092022_DA0F0TMDCD0_F0T_Management_Board_D_brd_V3_OCP.brd")
		(comment 1 "Grand Teton / footprints 1400-1401 of 1440")
	)
	(layers
		(0 "F.Cu" signal "TOP")
		(4 "In1.Cu" signal "GND")
		(6 "In2.Cu" signal "IN1")
		(8 "In3.Cu" signal "GND1")
		(10 "In4.Cu" signal "IN2")
		(12 "In5.Cu" signal "VCC")
		(14 "In6.Cu" signal "VCC1")
		(16 "In7.Cu" signal "IN3")
		(18 "In8.Cu" signal "GND2")
		(20 "In9.Cu" signal "IN4")
		(22 "In10.Cu" signal "GND3")
		(2 "B.Cu" signal "BOTTOM")
		(9 "F.Adhes" user "F.Adhesive")
		(11 "B.Adhes" user "B.Adhesive")
		(13 "F.Paste" user "Package Geometry/Pastemask Top")
		(15 "B.Paste" user "Package Geometry/Pastemask Bottom")
		(5 "F.SilkS" user "Ref Des/Silkscreen Top")
		(7 "B.SilkS" user "Ref Des/Silkscreen Bottom")
		(1 "F.Mask" user "Board Geometry/Soldermask Top")
		(3 "B.Mask" user "Board Geometry/Soldermask Bottom")
		(17 "Dwgs.User" user "User.Drawings")
		(19 "Cmts.User" user "User.Comments")
		(21 "Eco1.User" user "User.Eco1")
		(23 "Eco2.User" user "User.Eco2")
		(25 "Edge.Cuts" user "Board Geometry/Outline")
		(27 "Margin" user)
		(31 "F.CrtYd" user "Package Geometry/Place Bound Top")
		(29 "B.CrtYd" user "Package Geometry/Place Bound Bottom")
		(35 "F.Fab" user "Ref Des/Assembly Top")
		(33 "B.Fab" user "Ref Des/Assembly Bottom")
	)
	(footprint ""
		(layer "B.Cu")
		(at 32.766 -89.789 180)
		(property "Reference" "C257"
			(at 0 0 0)
			(layer "B.SilkS")
			(hide yes)
			(effects
				(font
					(size 1.27 1.27)
				)
				(justify mirror)
			)
		)
		(property "Value" ""
			(at 0 0 0)
			(layer "B.Fab")
			(effects
				(font
					(size 1.27 1.27)
				)
				(justify mirror)
			)
		)
		(duplicate_pad_numbers_are_jumpers no)
		(fp_line
			(start 0.7874 0.4064)
			(end 0.7874 -0.4064)
			(stroke
				(width 0.1524)
				(type default)
			)
			(layer "B.SilkS")
		)
		(fp_line
			(start 0.7874 -0.4064)
			(end -0.7874 -0.4064)
			(stroke
				(width 0.1524)
				(type default)
			)
			(layer "B.SilkS")
		)
		(fp_line
			(start -0.7874 0.4064)
			(end 0.7874 0.4064)
			(stroke
				(width 0.1524)
				(type default)
			)
			(layer "B.SilkS")
		)
		(fp_line
			(start -0.7874 -0.4064)
			(end -0.7874 0.4064)
			(stroke
				(width 0.1524)
				(type default)
			)
			(layer "B.SilkS")
		)
		(fp_line
			(start 0.67945 0.3048)
			(end 0.67945 -0.305054)
			(stroke
				(width 0.1)
				(type default)
			)
			(layer "B.Fab")
		)
		(fp_line
			(start 0.67945 -0.305054)
			(end 0.12065 -0.305054)
			(stroke
				(width 0.1)
				(type default)
			)
			(layer "B.Fab")
		)
		(fp_line
			(start 0.12065 0.3048)
			(end 0.67945 0.3048)
			(stroke
				(width 0.1)
				(type default)
			)
			(layer "B.Fab")
		)
		(fp_line
			(start 0.12065 0.2794)
			(end 0.12065 0.3048)
			(stroke
				(width 0.1)
				(type default)
			)
			(layer "B.Fab")
		)
		(fp_line
			(start 0.12065 -0.2794)
			(end -0.12065 -0.2794)
			(stroke
				(width 0.1)
				(type default)
			)
			(layer "B.Fab")
		)
		(fp_line
			(start 0.12065 -0.305054)
			(end 0.12065 -0.2794)
			(stroke
				(width 0.1)
				(type default)
			)
			(layer "B.Fab")
		)
		(fp_line
			(start -0.120396 0.3048)
			(end -0.120396 0.2794)
			(stroke
				(width 0.1)
				(type default)
			)
			(layer "B.Fab")
		)
		(fp_line
			(start -0.120396 0.2794)
			(end 0.12065 0.2794)
			(stroke
				(width 0.1)
				(type default)
			)
			(layer "B.Fab")
		)
		(fp_line
			(start -0.12065 -0.2794)
			(end -0.12065 -0.3048)
			(stroke
				(width 0.1)
				(type default)
			)
			(layer "B.Fab")
		)
		(fp_line
			(start -0.12065 -0.3048)
			(end -0.67945 -0.3048)
			(stroke
				(width 0.1)
				(type default)
			)
			(layer "B.Fab")
		)
		(fp_line
			(start -0.67945 0.3048)
			(end -0.120396 0.3048)
			(stroke
				(width 0.1)
				(type default)
			)
			(layer "B.Fab")
		)
		(fp_line
			(start -0.67945 -0.3048)
			(end -0.67945 0.3048)
			(stroke
				(width 0.1)
				(type default)
			)
			(layer "B.Fab")
		)
		(pad "1" smd circle
			(at 0.40005 0)
			(size 0 0)
			(layers "B.Cu" "B.Mask" "B.Paste")
			(net "PVCCIO_AUX_PLD")
		)
		(pad "2" smd circle
			(at -0.40005 0)
			(size 0 0)
			(layers "B.Cu" "B.Mask" "B.Paste")
			(net "GND")
		)
	)
	(footprint ""
		(layer "B.Cu")
		(at 45.419264 -34.637726 90)
		(property "Reference" "R138"
			(at 0 0 90)
			(layer "B.SilkS")
			(hide yes)
			(effects
				(font
					(size 1.27 1.27)
				)
				(justify mirror)
			)
		)
		(property "Value" ""
			(at 0 0 90)
			(layer "B.Fab")
			(effects
				(font
					(size 1.27 1.27)
				)
				(justify mirror)
			)
		)
		(duplicate_pad_numbers_are_jumpers no)
		(fp_line
			(start 0.7874 -0.4064)
			(end -0.7874 -0.4064)
			(stroke
				(width 0.1524)
				(type default)
			)
			(layer "B.SilkS")
		)
		(fp_line
			(start -0.7874 -0.4064)
			(end -0.7874 0.4064)
			(stroke
				(width 0.1524)
				(type default)
			)
			(layer "B.SilkS")
		)
		(fp_line
			(start 0.7874 0.4064)
			(end 0.7874 -0.4064)
			(stroke
				(width 0.1524)
				(type default)
			)
			(layer "B.SilkS")
		)
		(fp_line
			(start -0.7874 0.4064)
			(end 0.7874 0.4064)
			(stroke
				(width 0.1524)
				(type default)
			)
			(layer "B.SilkS")
		)
		(fp_line
			(start 0.67945 -0.305054)
			(end 0.12065 -0.305054)
			(stroke
				(width 0.1)
				(type default)
			)
			(layer "B.Fab")
		)
		(fp_line
			(start 0.12065 -0.305054)
			(end 0.12065 -0.2794)
			(stroke
				(width 0.1)
				(type default)
			)
			(layer "B.Fab")
		)
		(fp_line
			(start -0.12065 -0.3048)
			(end -0.67945 -0.3048)
			(stroke
				(width 0.1)
				(type default)
			)
			(layer "B.Fab")
		)
		(fp_line
			(start -0.67945 -0.3048)
			(end -0.67945 0.3048)
			(stroke
				(width 0.1)
				(type default)
			)
			(layer "B.Fab")
		)
		(fp_line
			(start 0.12065 -0.2794)
			(end -0.12065 -0.2794)
			(stroke
				(width 0.1)
				(type default)
			)
			(layer "B.Fab")
		)
		(fp_line
			(start -0.12065 -0.2794)
			(end -0.12065 -0.3048)
			(stroke
				(width 0.1)
				(type default)
			)
			(layer "B.Fab")
		)
		(fp_line
			(start 0.12065 0.2794)
			(end 0.12065 0.3048)
			(stroke
				(width 0.1)
				(type default)
			)
			(layer "B.Fab")
		)
		(fp_line
			(start -0.120396 0.2794)
			(end 0.12065 0.2794)
			(stroke
				(width 0.1)
				(type default)
			)
			(layer "B.Fab")
		)
		(fp_line
			(start 0.67945 0.3048)
			(end 0.67945 -0.305054)
			(stroke
				(width 0.1)
				(type default)
			)
			(layer "B.Fab")
		)
		(fp_line
			(start 0.12065 0.3048)
			(end 0.67945 0.3048)
			(stroke
				(width 0.1)
				(type default)
			)
			(layer "B.Fab")
		)
		(fp_line
			(start -0.120396 0.3048)
			(end -0.120396 0.2794)
			(stroke
				(width 0.1)
				(type default)
			)
			(layer "B.Fab")
		)
		(fp_line
			(start -0.67945 0.3048)
			(end -0.120396 0.3048)
			(stroke
				(width 0.1)
				(type default)
			)
			(layer "B.Fab")
		)
		(pad "1" smd circle
			(at 0.40005 0 270)
			(size 0 0)
			(layers "B.Cu" "B.Mask" "B.Paste")
			(net "SMB_BMC_MM4_R_SCL")
		)
		(pad "2" smd circle
			(at -0.40005 0 270)
			(size 0 0)
			(layers "B.Cu" "B.Mask" "B.Paste")
			(net "SMB_BMC_MM4_SCL")
		)
	)
)
